(kicad_pcb
	(version 20260206)
	(generator "pcbnew")
	(generator_version "10.0")
	(general
		(thickness 1.6)
		(legacy_teardrops no)
	)
	(paper "A4")
	(title_block
		(title "04192023_DAF0TMB3IC0_F0TG_MB_C_brd_V02_OCP.brd")
		(comment 1 "Grand Teton / footprints 7648-7654 of 8354")
	)
	(layers
		(0 "F.Cu" signal "TOP")
		(4 "In1.Cu" signal "GND")
		(6 "In2.Cu" signal "IN1")
		(8 "In3.Cu" signal "GND1")
		(10 "In4.Cu" signal "IN2")
		(12 "In5.Cu" signal "GND2")
		(14 "In6.Cu" signal "IN3")
		(16 "In7.Cu" signal "GND3")
		(18 "In8.Cu" signal "VCC")
		(20 "In9.Cu" signal "VCC1")
		(22 "In10.Cu" signal "GND4")
		(24 "In11.Cu" signal "IN4")
		(26 "In12.Cu" signal "GND5")
		(28 "In13.Cu" signal "IN5")
		(30 "In14.Cu" signal "GND6")
		(32 "In15.Cu" signal "IN6")
		(34 "In16.Cu" signal "GND7")
		(2 "B.Cu" signal "BOTTOM")
		(9 "F.Adhes" user "F.Adhesive")
		(11 "B.Adhes" user "B.Adhesive")
		(13 "F.Paste" user "Package Geometry/Pastemask Top")
		(15 "B.Paste" user "Package Geometry/Pastemask Bottom")
		(5 "F.SilkS" user "Ref Des/Silkscreen Top")
		(7 "B.SilkS" user "Ref Des/Silkscreen Bottom")
		(1 "F.Mask" user "Board Geometry/Soldermask Top")
		(3 "B.Mask" user "Board Geometry/Soldermask Bottom")
		(17 "Dwgs.User" user "User.Drawings")
		(19 "Cmts.User" user "User.Comments")
		(21 "Eco1.User" user "User.Eco1")
		(23 "Eco2.User" user "User.Eco2")
		(25 "Edge.Cuts" user "Board Geometry/Outline")
		(27 "Margin" user)
		(31 "F.CrtYd" user "Package Geometry/Place Bound Top")
		(29 "B.CrtYd" user "Package Geometry/Place Bound Bottom")
		(35 "F.Fab" user "Ref Des/Assembly Top")
		(33 "B.Fab" user "Ref Des/Assembly Bottom")
	)
	(footprint ""
		(layer "B.Cu")
		(at 348.418912 -259.729986 180)
		(property "Reference" "C2631"
			(at 0 0 0)
			(layer "B.SilkS")
			(hide yes)
			(effects
				(font
					(size 1.27 1.27)
				)
				(justify mirror)
			)
		)
		(property "Value" ""
			(at 0 0 0)
			(layer "B.Fab")
			(effects
				(font
					(size 1.27 1.27)
				)
				(justify mirror)
			)
		)
		(duplicate_pad_numbers_are_jumpers no)
		(fp_line
			(start 0.7874 0.4064)
			(end 0.7874 -0.4064)
			(stroke
				(width 0.1524)
				(type default)
			)
			(layer "B.SilkS")
		)
		(fp_line
			(start 0.7874 -0.4064)
			(end -0.7874 -0.4064)
			(stroke
				(width 0.1524)
				(type default)
			)
			(layer "B.SilkS")
		)
		(fp_line
			(start -0.7874 0.4064)
			(end 0.7874 0.4064)
			(stroke
				(width 0.1524)
				(type default)
			)
			(layer "B.SilkS")
		)
		(fp_line
			(start -0.7874 -0.4064)
			(end -0.7874 0.4064)
			(stroke
				(width 0.1524)
				(type default)
			)
			(layer "B.SilkS")
		)
		(fp_line
			(start 0.67945 0.3048)
			(end 0.67945 -0.305054)
			(stroke
				(width 0.1)
				(type default)
			)
			(layer "B.Fab")
		)
		(fp_line
			(start 0.67945 -0.305054)
			(end 0.12065 -0.305054)
			(stroke
				(width 0.1)
				(type default)
			)
			(layer "B.Fab")
		)
		(fp_line
			(start 0.12065 0.3048)
			(end 0.67945 0.3048)
			(stroke
				(width 0.1)
				(type default)
			)
			(layer "B.Fab")
		)
		(fp_line
			(start 0.12065 0.2794)
			(end 0.12065 0.3048)
			(stroke
				(width 0.1)
				(type default)
			)
			(layer "B.Fab")
		)
		(fp_line
			(start 0.12065 -0.2794)
			(end -0.12065 -0.2794)
			(stroke
				(width 0.1)
				(type default)
			)
			(layer "B.Fab")
		)
		(fp_line
			(start 0.12065 -0.305054)
			(end 0.12065 -0.2794)
			(stroke
				(width 0.1)
				(type default)
			)
			(layer "B.Fab")
		)
		(fp_line
			(start -0.120396 0.3048)
			(end -0.120396 0.2794)
			(stroke
				(width 0.1)
				(type default)
			)
			(layer "B.Fab")
		)
		(fp_line
			(start -0.120396 0.2794)
			(end 0.12065 0.2794)
			(stroke
				(width 0.1)
				(type default)
			)
			(layer "B.Fab")
		)
		(fp_line
			(start -0.12065 -0.2794)
			(end -0.12065 -0.3048)
			(stroke
				(width 0.1)
				(type default)
			)
			(layer "B.Fab")
		)
		(fp_line
			(start -0.12065 -0.3048)
			(end -0.67945 -0.3048)
			(stroke
				(width 0.1)
				(type default)
			)
			(layer "B.Fab")
		)
		(fp_line
			(start -0.67945 0.3048)
			(end -0.120396 0.3048)
			(stroke
				(width 0.1)
				(type default)
			)
			(layer "B.Fab")
		)
		(fp_line
			(start -0.67945 -0.3048)
			(end -0.67945 0.3048)
			(stroke
				(width 0.1)
				(type default)
			)
			(layer "B.Fab")
		)
		(pad "1" smd circle
			(at 0.40005 0)
			(size 0 0)
			(layers "B.Cu" "B.Mask" "B.Paste")
			(net "PVDDIO_P0")
		)
		(pad "2" smd circle
			(at -0.40005 0)
			(size 0 0)
			(layers "B.Cu" "B.Mask" "B.Paste")
			(net "GND")
		)
	)
	(footprint ""
		(layer "B.Cu")
		(at 123.441206 -408.517344 90)
		(property "Reference" "C6729"
			(at 0 0 90)
			(layer "B.SilkS")
			(hide yes)
			(effects
				(font
					(size 1.27 1.27)
				)
				(justify mirror)
			)
		)
		(property "Value" ""
			(at 0 0 90)
			(layer "B.Fab")
			(effects
				(font
					(size 1.27 1.27)
				)
				(justify mirror)
			)
		)
		(duplicate_pad_numbers_are_jumpers no)
		(fp_line
			(start 0.299974 -0.150114)
			(end -0.299974 -0.150114)
			(stroke
				(width 0.1)
				(type default)
			)
			(layer "B.Fab")
		)
		(fp_line
			(start -0.299974 -0.150114)
			(end -0.299974 0.150114)
			(stroke
				(width 0.1)
				(type default)
			)
			(layer "B.Fab")
		)
		(fp_line
			(start 0.299974 0.150114)
			(end 0.299974 -0.150114)
			(stroke
				(width 0.1)
				(type default)
			)
			(layer "B.Fab")
		)
		(fp_line
			(start -0.299974 0.150114)
			(end 0.299974 0.150114)
			(stroke
				(width 0.1)
				(type default)
			)
			(layer "B.Fab")
		)
		(pad "1" smd rect
			(at 0.2667 0 270)
			(size 0.3048 0.381)
			(layers "B.Cu" "B.Mask" "B.Paste")
			(net "P5E_CPU1_P3_TX_BUF_C_DP<2>")
		)
		(pad "2" smd rect
			(at -0.2667 0 270)
			(size 0.3048 0.381)
			(layers "B.Cu" "B.Mask" "B.Paste")
			(net "P5E_CPU1_P3_TX_BUF_DP<2>")
		)
	)
	(footprint ""
		(layer "B.Cu")
		(at 372.937278 -140.456158)
		(property "Reference" "C468"
			(at 0 0 0)
			(layer "B.SilkS")
			(hide yes)
			(effects
				(font
					(size 1.27 1.27)
				)
				(justify mirror)
			)
		)
		(property "Value" ""
			(at 0 0 0)
			(layer "B.Fab")
			(effects
				(font
					(size 1.27 1.27)
				)
				(justify mirror)
			)
		)
		(duplicate_pad_numbers_are_jumpers no)
		(fp_line
			(start -0.7874 -0.4064)
			(end -0.7874 0.4064)
			(stroke
				(width 0.1524)
				(type default)
			)
			(layer "B.SilkS")
		)
		(fp_line
			(start -0.7874 0.4064)
			(end 0.7874 0.4064)
			(stroke
				(width 0.1524)
				(type default)
			)
			(layer "B.SilkS")
		)
		(fp_line
			(start 0.7874 -0.4064)
			(end -0.7874 -0.4064)
			(stroke
				(width 0.1524)
				(type default)
			)
			(layer "B.SilkS")
		)
		(fp_line
			(start 0.7874 0.4064)
			(end 0.7874 -0.4064)
			(stroke
				(width 0.1524)
				(type default)
			)
			(layer "B.SilkS")
		)
		(fp_line
			(start -0.67945 -0.3048)
			(end -0.67945 0.3048)
			(stroke
				(width 0.1)
				(type default)
			)
			(layer "B.Fab")
		)
		(fp_line
			(start -0.67945 0.3048)
			(end -0.120396 0.3048)
			(stroke
				(width 0.1)
				(type default)
			)
			(layer "B.Fab")
		)
		(fp_line
			(start -0.12065 -0.3048)
			(end -0.67945 -0.3048)
			(stroke
				(width 0.1)
				(type default)
			)
			(layer "B.Fab")
		)
		(fp_line
			(start -0.12065 -0.2794)
			(end -0.12065 -0.3048)
			(stroke
				(width 0.1)
				(type default)
			)
			(layer "B.Fab")
		)
		(fp_line
			(start -0.120396 0.2794)
			(end 0.12065 0.2794)
			(stroke
				(width 0.1)
				(type default)
			)
			(layer "B.Fab")
		)
		(fp_line
			(start -0.120396 0.3048)
			(end -0.120396 0.2794)
			(stroke
				(width 0.1)
				(type default)
			)
			(layer "B.Fab")
		)
		(fp_line
			(start 0.12065 -0.305054)
			(end 0.12065 -0.2794)
			(stroke
				(width 0.1)
				(type default)
			)
			(layer "B.Fab")
		)
		(fp_line
			(start 0.12065 -0.2794)
			(end -0.12065 -0.2794)
			(stroke
				(width 0.1)
				(type default)
			)
			(layer "B.Fab")
		)
		(fp_line
			(start 0.12065 0.2794)
			(end 0.12065 0.3048)
			(stroke
				(width 0.1)
				(type default)
			)
			(layer "B.Fab")
		)
		(fp_line
			(start 0.12065 0.3048)
			(end 0.67945 0.3048)
			(stroke
				(width 0.1)
				(type default)
			)
			(layer "B.Fab")
		)
		(fp_line
			(start 0.67945 -0.305054)
			(end 0.12065 -0.305054)
			(stroke
				(width 0.1)
				(type default)
			)
			(layer "B.Fab")
		)
		(fp_line
			(start 0.67945 0.3048)
			(end 0.67945 -0.305054)
			(stroke
				(width 0.1)
				(type default)
			)
			(layer "B.Fab")
		)
		(pad "1" smd circle
			(at 0.40005 0 180)
			(size 0 0)
			(layers "B.Cu" "B.Mask" "B.Paste")
			(net "PVDDCR_CPU0_P0_EN_R")
		)
		(pad "2" smd circle
			(at -0.40005 0 180)
			(size 0 0)
			(layers "B.Cu" "B.Mask" "B.Paste")
			(net "GND")
		)
	)
	(footprint ""
		(layer "B.Cu")
		(at 109.550454 -33.603438 180)
		(property "Reference" "C6095"
			(at 0 0 0)
			(layer "B.SilkS")
			(hide yes)
			(effects
				(font
					(size 1.27 1.27)
				)
				(justify mirror)
			)
		)
		(property "Value" ""
			(at 0 0 0)
			(layer "B.Fab")
			(effects
				(font
					(size 1.27 1.27)
				)
				(justify mirror)
			)
		)
		(duplicate_pad_numbers_are_jumpers no)
		(fp_line
			(start 0.7874 0.4064)
			(end 0.7874 -0.4064)
			(stroke
				(width 0.1524)
				(type default)
			)
			(layer "B.SilkS")
		)
		(fp_line
			(start 0.7874 -0.4064)
			(end -0.7874 -0.4064)
			(stroke
				(width 0.1524)
				(type default)
			)
			(layer "B.SilkS")
		)
		(fp_line
			(start -0.7874 0.4064)
			(end 0.7874 0.4064)
			(stroke
				(width 0.1524)
				(type default)
			)
			(layer "B.SilkS")
		)
		(fp_line
			(start -0.7874 -0.4064)
			(end -0.7874 0.4064)
			(stroke
				(width 0.1524)
				(type default)
			)
			(layer "B.SilkS")
		)
		(fp_line
			(start 0.67945 0.3048)
			(end 0.67945 -0.305054)
			(stroke
				(width 0.1)
				(type default)
			)
			(layer "B.Fab")
		)
		(fp_line
			(start 0.67945 -0.305054)
			(end 0.12065 -0.305054)
			(stroke
				(width 0.1)
				(type default)
			)
			(layer "B.Fab")
		)
		(fp_line
			(start 0.12065 0.3048)
			(end 0.67945 0.3048)
			(stroke
				(width 0.1)
				(type default)
			)
			(layer "B.Fab")
		)
		(fp_line
			(start 0.12065 0.2794)
			(end 0.12065 0.3048)
			(stroke
				(width 0.1)
				(type default)
			)
			(layer "B.Fab")
		)
		(fp_line
			(start 0.12065 -0.2794)
			(end -0.12065 -0.2794)
			(stroke
				(width 0.1)
				(type default)
			)
			(layer "B.Fab")
		)
		(fp_line
			(start 0.12065 -0.305054)
			(end 0.12065 -0.2794)
			(stroke
				(width 0.1)
				(type default)
			)
			(layer "B.Fab")
		)
		(fp_line
			(start -0.120396 0.3048)
			(end -0.120396 0.2794)
			(stroke
				(width 0.1)
				(type default)
			)
			(layer "B.Fab")
		)
		(fp_line
			(start -0.120396 0.2794)
			(end 0.12065 0.2794)
			(stroke
				(width 0.1)
				(type default)
			)
			(layer "B.Fab")
		)
		(fp_line
			(start -0.12065 -0.2794)
			(end -0.12065 -0.3048)
			(stroke
				(width 0.1)
				(type default)
			)
			(layer "B.Fab")
		)
		(fp_line
			(start -0.12065 -0.3048)
			(end -0.67945 -0.3048)
			(stroke
				(width 0.1)
				(type default)
			)
			(layer "B.Fab")
		)
		(fp_line
			(start -0.67945 0.3048)
			(end -0.120396 0.3048)
			(stroke
				(width 0.1)
				(type default)
			)
			(layer "B.Fab")
		)
		(fp_line
			(start -0.67945 -0.3048)
			(end -0.67945 0.3048)
			(stroke
				(width 0.1)
				(type default)
			)
			(layer "B.Fab")
		)
		(pad "1" smd circle
			(at 0.40005 0)
			(size 0 0)
			(layers "B.Cu" "B.Mask" "B.Paste")
			(net "P3V3_AUX_CPU0_USB2_AVDD33")
		)
		(pad "2" smd circle
			(at -0.40005 0)
			(size 0 0)
			(layers "B.Cu" "B.Mask" "B.Paste")
			(net "GND")
		)
	)
	(footprint ""
		(layer "B.Cu")
		(at 292.608 -426.085 -90)
		(property "Reference" "R2668"
			(at 0 0 90)
			(layer "B.SilkS")
			(hide yes)
			(effects
				(font
					(size 1.27 1.27)
				)
				(justify mirror)
			)
		)
		(property "Value" ""
			(at 0 0 90)
			(layer "B.Fab")
			(effects
				(font
					(size 1.27 1.27)
				)
				(justify mirror)
			)
		)
		(duplicate_pad_numbers_are_jumpers no)
		(fp_line
			(start -0.7874 0.4064)
			(end 0.7874 0.4064)
			(stroke
				(width 0.1524)
				(type default)
			)
			(layer "B.SilkS")
		)
		(fp_line
			(start 0.7874 0.4064)
			(end 0.7874 -0.4064)
			(stroke
				(width 0.1524)
				(type default)
			)
			(layer "B.SilkS")
		)
		(fp_line
			(start -0.7874 -0.4064)
			(end -0.7874 0.4064)
			(stroke
				(width 0.1524)
				(type default)
			)
			(layer "B.SilkS")
		)
		(fp_line
			(start 0.7874 -0.4064)
			(end -0.7874 -0.4064)
			(stroke
				(width 0.1524)
				(type default)
			)
			(layer "B.SilkS")
		)
		(fp_line
			(start -0.67945 0.3048)
			(end -0.120396 0.3048)
			(stroke
				(width 0.1)
				(type default)
			)
			(layer "B.Fab")
		)
		(fp_line
			(start -0.120396 0.3048)
			(end -0.120396 0.2794)
			(stroke
				(width 0.1)
				(type default)
			)
			(layer "B.Fab")
		)
		(fp_line
			(start 0.12065 0.3048)
			(end 0.67945 0.3048)
			(stroke
				(width 0.1)
				(type default)
			)
			(layer "B.Fab")
		)
		(fp_line
			(start 0.67945 0.3048)
			(end 0.67945 -0.305054)
			(stroke
				(width 0.1)
				(type default)
			)
			(layer "B.Fab")
		)
		(fp_line
			(start -0.120396 0.2794)
			(end 0.12065 0.2794)
			(stroke
				(width 0.1)
				(type default)
			)
			(layer "B.Fab")
		)
		(fp_line
			(start 0.12065 0.2794)
			(end 0.12065 0.3048)
			(stroke
				(width 0.1)
				(type default)
			)
			(layer "B.Fab")
		)
		(fp_line
			(start -0.12065 -0.2794)
			(end -0.12065 -0.3048)
			(stroke
				(width 0.1)
				(type default)
			)
			(layer "B.Fab")
		)
		(fp_line
			(start 0.12065 -0.2794)
			(end -0.12065 -0.2794)
			(stroke
				(width 0.1)
				(type default)
			)
			(layer "B.Fab")
		)
		(fp_line
			(start -0.67945 -0.3048)
			(end -0.67945 0.3048)
			(stroke
				(width 0.1)
				(type default)
			)
			(layer "B.Fab")
		)
		(fp_line
			(start -0.12065 -0.3048)
			(end -0.67945 -0.3048)
			(stroke
				(width 0.1)
				(type default)
			)
			(layer "B.Fab")
		)
		(fp_line
			(start 0.12065 -0.305054)
			(end 0.12065 -0.2794)
			(stroke
				(width 0.1)
				(type default)
			)
			(layer "B.Fab")
		)
		(fp_line
			(start 0.67945 -0.305054)
			(end 0.12065 -0.305054)
			(stroke
				(width 0.1)
				(type default)
			)
			(layer "B.Fab")
		)
		(pad "1" smd circle
			(at 0.40005 0 90)
			(size 0 0)
			(layers "B.Cu" "B.Mask" "B.Paste")
			(net "P3V3_AUX")
		)
		(pad "2" smd circle
			(at -0.40005 0 90)
			(size 0 0)
			(layers "B.Cu" "B.Mask" "B.Paste")
			(net "I3C_BMC_SWB_BUF_R_SDA")
		)
	)
	(footprint ""
		(layer "B.Cu")
		(at 59.401202 -195.926964 180)
		(property "Reference" "R1687"
			(at 0 0 0)
			(layer "B.SilkS")
			(hide yes)
			(effects
				(font
					(size 1.27 1.27)
				)
				(justify mirror)
			)
		)
		(property "Value" ""
			(at 0 0 0)
			(layer "B.Fab")
			(effects
				(font
					(size 1.27 1.27)
				)
				(justify mirror)
			)
		)
		(duplicate_pad_numbers_are_jumpers no)
		(fp_line
			(start 0.7874 0.4064)
			(end 0.7874 -0.4064)
			(stroke
				(width 0.1524)
				(type default)
			)
			(layer "B.SilkS")
		)
		(fp_line
			(start 0.7874 -0.4064)
			(end -0.7874 -0.4064)
			(stroke
				(width 0.1524)
				(type default)
			)
			(layer "B.SilkS")
		)
		(fp_line
			(start -0.7874 0.4064)
			(end 0.7874 0.4064)
			(stroke
				(width 0.1524)
				(type default)
			)
			(layer "B.SilkS")
		)
		(fp_line
			(start -0.7874 -0.4064)
			(end -0.7874 0.4064)
			(stroke
				(width 0.1524)
				(type default)
			)
			(layer "B.SilkS")
		)
		(fp_line
			(start 0.67945 0.3048)
			(end 0.67945 -0.305054)
			(stroke
				(width 0.1)
				(type default)
			)
			(layer "B.Fab")
		)
		(fp_line
			(start 0.67945 -0.305054)
			(end 0.12065 -0.305054)
			(stroke
				(width 0.1)
				(type default)
			)
			(layer "B.Fab")
		)
		(fp_line
			(start 0.12065 0.3048)
			(end 0.67945 0.3048)
			(stroke
				(width 0.1)
				(type default)
			)
			(layer "B.Fab")
		)
		(fp_line
			(start 0.12065 0.2794)
			(end 0.12065 0.3048)
			(stroke
				(width 0.1)
				(type default)
			)
			(layer "B.Fab")
		)
		(fp_line
			(start 0.12065 -0.2794)
			(end -0.12065 -0.2794)
			(stroke
				(width 0.1)
				(type default)
			)
			(layer "B.Fab")
		)
		(fp_line
			(start 0.12065 -0.305054)
			(end 0.12065 -0.2794)
			(stroke
				(width 0.1)
				(type default)
			)
			(layer "B.Fab")
		)
		(fp_line
			(start -0.120396 0.3048)
			(end -0.120396 0.2794)
			(stroke
				(width 0.1)
				(type default)
			)
			(layer "B.Fab")
		)
		(fp_line
			(start -0.120396 0.2794)
			(end 0.12065 0.2794)
			(stroke
				(width 0.1)
				(type default)
			)
			(layer "B.Fab")
		)
		(fp_line
			(start -0.12065 -0.2794)
			(end -0.12065 -0.3048)
			(stroke
				(width 0.1)
				(type default)
			)
			(layer "B.Fab")
		)
		(fp_line
			(start -0.12065 -0.3048)
			(end -0.67945 -0.3048)
			(stroke
				(width 0.1)
				(type default)
			)
			(layer "B.Fab")
		)
		(fp_line
			(start -0.67945 0.3048)
			(end -0.120396 0.3048)
			(stroke
				(width 0.1)
				(type default)
			)
			(layer "B.Fab")
		)
		(fp_line
			(start -0.67945 -0.3048)
			(end -0.67945 0.3048)
			(stroke
				(width 0.1)
				(type default)
			)
			(layer "B.Fab")
		)
		(pad "1" smd circle
			(at 0.40005 0)
			(size 0 0)
			(layers "B.Cu" "B.Mask" "B.Paste")
			(net "I3C_SPD_DDRAF_CPU1_SDA")
		)
		(pad "2" smd circle
			(at -0.40005 0)
			(size 0 0)
			(layers "B.Cu" "B.Mask" "B.Paste")
			(net "I3C_SPD_DDRA_CPU1_SDA")
		)
	)
	(footprint ""
		(layer "B.Cu")
		(at 121.579386 -266.005564)
		(property "Reference" "C2480"
			(at 0 0 0)
			(layer "B.SilkS")
			(hide yes)
			(effects
				(font
					(size 1.27 1.27)
				)
				(justify mirror)
			)
		)
		(property "Value" ""
			(at 0 0 0)
			(layer "B.Fab")
			(effects
				(font
					(size 1.27 1.27)
				)
				(justify mirror)
			)
		)
		(duplicate_pad_numbers_are_jumpers no)
		(fp_line
			(start -0.7874 -0.4064)
			(end -0.7874 0.4064)
			(stroke
				(width 0.1524)
				(type default)
			)
			(layer "B.SilkS")
		)
		(fp_line
			(start -0.7874 0.4064)
			(end 0.7874 0.4064)
			(stroke
				(width 0.1524)
				(type default)
			)
			(layer "B.SilkS")
		)
		(fp_line
			(start 0.7874 -0.4064)
			(end -0.7874 -0.4064)
			(stroke
				(width 0.1524)
				(type default)
			)
			(layer "B.SilkS")
		)
		(fp_line
			(start 0.7874 0.4064)
			(end 0.7874 -0.4064)
			(stroke
				(width 0.1524)
				(type default)
			)
			(layer "B.SilkS")
		)
		(fp_line
			(start -0.67945 -0.3048)
			(end -0.67945 0.3048)
			(stroke
				(width 0.1)
				(type default)
			)
			(layer "B.Fab")
		)
		(fp_line
			(start -0.67945 0.3048)
			(end -0.120396 0.3048)
			(stroke
				(width 0.1)
				(type default)
			)
			(layer "B.Fab")
		)
		(fp_line
			(start -0.12065 -0.3048)
			(end -0.67945 -0.3048)
			(stroke
				(width 0.1)
				(type default)
			)
			(layer "B.Fab")
		)
		(fp_line
			(start -0.12065 -0.2794)
			(end -0.12065 -0.3048)
			(stroke
				(width 0.1)
				(type default)
			)
			(layer "B.Fab")
		)
		(fp_line
			(start -0.120396 0.2794)
			(end 0.12065 0.2794)
			(stroke
				(width 0.1)
				(type default)
			)
			(layer "B.Fab")
		)
		(fp_line
			(start -0.120396 0.3048)
			(end -0.120396 0.2794)
			(stroke
				(width 0.1)
				(type default)
			)
			(layer "B.Fab")
		)
		(fp_line
			(start 0.12065 -0.305054)
			(end 0.12065 -0.2794)
			(stroke
				(width 0.1)
				(type default)
			)
			(layer "B.Fab")
		)
		(fp_line
			(start 0.12065 -0.2794)
			(end -0.12065 -0.2794)
			(stroke
				(width 0.1)
				(type default)
			)
			(layer "B.Fab")
		)
		(fp_line
			(start 0.12065 0.2794)
			(end 0.12065 0.3048)
			(stroke
				(width 0.1)
				(type default)
			)
			(layer "B.Fab")
		)
		(fp_line
			(start 0.12065 0.3048)
			(end 0.67945 0.3048)
			(stroke
				(width 0.1)
				(type default)
			)
			(layer "B.Fab")
		)
		(fp_line
			(start 0.67945 -0.305054)
			(end 0.12065 -0.305054)
			(stroke
				(width 0.1)
				(type default)
			)
			(layer "B.Fab")
		)
		(fp_line
			(start 0.67945 0.3048)
			(end 0.67945 -0.305054)
			(stroke
				(width 0.1)
				(type default)
			)
			(layer "B.Fab")
		)
		(pad "1" smd circle
			(at 0.40005 0 180)
			(size 0 0)
			(layers "B.Cu" "B.Mask" "B.Paste")
			(net "PVDD11_S3_P1")
		)
		(pad "2" smd circle
			(at -0.40005 0 180)
			(size 0 0)
			(layers "B.Cu" "B.Mask" "B.Paste")
			(net "GND")
		)
	)
)
